(kicad_pcb
	(version 20260206)
	(generator "pcbnew")
	(generator_version "10.0")
	(general
		(thickness 1.6)
		(legacy_teardrops no)
	)
	(paper "A4")
	(title_block
		(title "01162023_DA0F0TEBIF0_F0T_Expander_BD_F_brd_V02_OCP.brd")
		(comment 1 "Grand Teton / footprints 1995-2000 of 9728")
	)
	(layers
		(0 "F.Cu" signal "TOP")
		(4 "In1.Cu" signal "GND")
		(6 "In2.Cu" signal "VCC")
		(8 "In3.Cu" signal "VCC1")
		(10 "In4.Cu" signal "GND1")
		(12 "In5.Cu" signal "IN1")
		(14 "In6.Cu" signal "GND2")
		(16 "In7.Cu" signal "IN2")
		(18 "In8.Cu" signal "GND3")
		(20 "In9.Cu" signal "IN3")
		(22 "In10.Cu" signal "GND4")
		(24 "In11.Cu" signal "IN4")
		(26 "In12.Cu" signal "GND5")
		(28 "In13.Cu" signal "IN5")
		(30 "In14.Cu" signal "GND6")
		(32 "In15.Cu" signal "IN6")
		(34 "In16.Cu" signal "GND7")
		(2 "B.Cu" signal "BOTTOM")
		(9 "F.Adhes" user "F.Adhesive")
		(11 "B.Adhes" user "B.Adhesive")
		(13 "F.Paste" user "Package Geometry/Pastemask Top")
		(15 "B.Paste" user "Package Geometry/Pastemask Bottom")
		(5 "F.SilkS" user "Ref Des/Silkscreen Top")
		(7 "B.SilkS" user "Ref Des/Silkscreen Bottom")
		(1 "F.Mask" user "Board Geometry/Soldermask Top")
		(3 "B.Mask" user "Board Geometry/Soldermask Bottom")
		(17 "Dwgs.User" user "User.Drawings")
		(19 "Cmts.User" user "User.Comments")
		(21 "Eco1.User" user "User.Eco1")
		(23 "Eco2.User" user "User.Eco2")
		(25 "Edge.Cuts" user "Board Geometry/Outline")
		(27 "Margin" user)
		(31 "F.CrtYd" user "Package Geometry/Place Bound Top")
		(29 "B.CrtYd" user "Package Geometry/Place Bound Bottom")
		(35 "F.Fab" user "Ref Des/Assembly Top")
		(33 "B.Fab" user "Ref Des/Assembly Bottom")
	)
	(footprint ""
		(layer "F.Cu")
		(at 455.542396 -235.200444 -90)
		(property "Reference" "R6608"
			(at 0 0 270)
			(layer "F.SilkS")
			(hide yes)
			(effects
				(font
					(size 1.27 1.27)
				)
			)
		)
		(property "Value" ""
			(at 0 0 270)
			(layer "F.Fab")
			(effects
				(font
					(size 1.27 1.27)
				)
			)
		)
		(duplicate_pad_numbers_are_jumpers no)
		(fp_line
			(start -0.7874 0.4064)
			(end -0.7874 -0.4064)
			(stroke
				(width 0.1524)
				(type default)
			)
			(layer "F.SilkS")
		)
		(fp_line
			(start 0.7874 0.4064)
			(end -0.7874 0.4064)
			(stroke
				(width 0.1524)
				(type default)
			)
			(layer "F.SilkS")
		)
		(fp_line
			(start -0.7874 -0.4064)
			(end 0.7874 -0.4064)
			(stroke
				(width 0.1524)
				(type default)
			)
			(layer "F.SilkS")
		)
		(fp_line
			(start 0.7874 -0.4064)
			(end 0.7874 0.4064)
			(stroke
				(width 0.1524)
				(type default)
			)
			(layer "F.SilkS")
		)
		(fp_line
			(start -0.67945 0.3048)
			(end -0.67945 -0.305054)
			(stroke
				(width 0.1)
				(type default)
			)
			(layer "F.Fab")
		)
		(fp_line
			(start -0.12065 0.3048)
			(end -0.67945 0.3048)
			(stroke
				(width 0.1)
				(type default)
			)
			(layer "F.Fab")
		)
		(fp_line
			(start 0.120396 0.3048)
			(end 0.120396 0.2794)
			(stroke
				(width 0.1)
				(type default)
			)
			(layer "F.Fab")
		)
		(fp_line
			(start 0.67945 0.3048)
			(end 0.120396 0.3048)
			(stroke
				(width 0.1)
				(type default)
			)
			(layer "F.Fab")
		)
		(fp_line
			(start -0.12065 0.2794)
			(end -0.12065 0.3048)
			(stroke
				(width 0.1)
				(type default)
			)
			(layer "F.Fab")
		)
		(fp_line
			(start 0.120396 0.2794)
			(end -0.12065 0.2794)
			(stroke
				(width 0.1)
				(type default)
			)
			(layer "F.Fab")
		)
		(fp_line
			(start -0.12065 -0.2794)
			(end 0.12065 -0.2794)
			(stroke
				(width 0.1)
				(type default)
			)
			(layer "F.Fab")
		)
		(fp_line
			(start 0.12065 -0.2794)
			(end 0.12065 -0.3048)
			(stroke
				(width 0.1)
				(type default)
			)
			(layer "F.Fab")
		)
		(fp_line
			(start 0.12065 -0.3048)
			(end 0.67945 -0.3048)
			(stroke
				(width 0.1)
				(type default)
			)
			(layer "F.Fab")
		)
		(fp_line
			(start 0.67945 -0.3048)
			(end 0.67945 0.3048)
			(stroke
				(width 0.1)
				(type default)
			)
			(layer "F.Fab")
		)
		(fp_line
			(start -0.67945 -0.305054)
			(end -0.12065 -0.305054)
			(stroke
				(width 0.1)
				(type default)
			)
			(layer "F.Fab")
		)
		(fp_line
			(start -0.12065 -0.305054)
			(end -0.12065 -0.2794)
			(stroke
				(width 0.1)
				(type default)
			)
			(layer "F.Fab")
		)
		(pad "1" smd circle
			(at -0.40005 0 270)
			(size 0 0)
			(layers "F.Cu" "F.Mask" "F.Paste")
			(net "UART_PEX0_SDB_BUF_R_TX")
		)
		(pad "2" smd circle
			(at 0.40005 0 270)
			(size 0 0)
			(layers "F.Cu" "F.Mask" "F.Paste")
			(net "UART_PEX0_SDB_CP2108_TX")
		)
	)
	(footprint ""
		(layer "F.Cu")
		(at 428.641764 -27.006296 -90)
		(property "Reference" "PR7130"
			(at 0 0 270)
			(layer "F.SilkS")
			(hide yes)
			(effects
				(font
					(size 1.27 1.27)
				)
			)
		)
		(property "Value" ""
			(at 0 0 270)
			(layer "F.Fab")
			(effects
				(font
					(size 1.27 1.27)
				)
			)
		)
		(duplicate_pad_numbers_are_jumpers no)
		(fp_line
			(start -0.7874 0.4064)
			(end -0.7874 -0.4064)
			(stroke
				(width 0.1524)
				(type default)
			)
			(layer "F.SilkS")
		)
		(fp_line
			(start 0.7874 0.4064)
			(end -0.7874 0.4064)
			(stroke
				(width 0.1524)
				(type default)
			)
			(layer "F.SilkS")
		)
		(fp_line
			(start -0.7874 -0.4064)
			(end 0.7874 -0.4064)
			(stroke
				(width 0.1524)
				(type default)
			)
			(layer "F.SilkS")
		)
		(fp_line
			(start 0.7874 -0.4064)
			(end 0.7874 0.4064)
			(stroke
				(width 0.1524)
				(type default)
			)
			(layer "F.SilkS")
		)
		(fp_line
			(start -0.67945 0.3048)
			(end -0.67945 -0.305054)
			(stroke
				(width 0.1)
				(type default)
			)
			(layer "F.Fab")
		)
		(fp_line
			(start -0.12065 0.3048)
			(end -0.67945 0.3048)
			(stroke
				(width 0.1)
				(type default)
			)
			(layer "F.Fab")
		)
		(fp_line
			(start 0.120396 0.3048)
			(end 0.120396 0.2794)
			(stroke
				(width 0.1)
				(type default)
			)
			(layer "F.Fab")
		)
		(fp_line
			(start 0.67945 0.3048)
			(end 0.120396 0.3048)
			(stroke
				(width 0.1)
				(type default)
			)
			(layer "F.Fab")
		)
		(fp_line
			(start -0.12065 0.2794)
			(end -0.12065 0.3048)
			(stroke
				(width 0.1)
				(type default)
			)
			(layer "F.Fab")
		)
		(fp_line
			(start 0.120396 0.2794)
			(end -0.12065 0.2794)
			(stroke
				(width 0.1)
				(type default)
			)
			(layer "F.Fab")
		)
		(fp_line
			(start -0.12065 -0.2794)
			(end 0.12065 -0.2794)
			(stroke
				(width 0.1)
				(type default)
			)
			(layer "F.Fab")
		)
		(fp_line
			(start 0.12065 -0.2794)
			(end 0.12065 -0.3048)
			(stroke
				(width 0.1)
				(type default)
			)
			(layer "F.Fab")
		)
		(fp_line
			(start 0.12065 -0.3048)
			(end 0.67945 -0.3048)
			(stroke
				(width 0.1)
				(type default)
			)
			(layer "F.Fab")
		)
		(fp_line
			(start 0.67945 -0.3048)
			(end 0.67945 0.3048)
			(stroke
				(width 0.1)
				(type default)
			)
			(layer "F.Fab")
		)
		(fp_line
			(start -0.67945 -0.305054)
			(end -0.12065 -0.305054)
			(stroke
				(width 0.1)
				(type default)
			)
			(layer "F.Fab")
		)
		(fp_line
			(start -0.12065 -0.305054)
			(end -0.12065 -0.2794)
			(stroke
				(width 0.1)
				(type default)
			)
			(layer "F.Fab")
		)
		(pad "1" smd circle
			(at -0.40005 0 270)
			(size 0 0)
			(layers "F.Cu" "F.Mask" "F.Paste")
			(net "P3V3_SSD15_CO_ILIMIT")
		)
		(pad "2" smd circle
			(at 0.40005 0 270)
			(size 0 0)
			(layers "F.Cu" "F.Mask" "F.Paste")
			(net "GND")
		)
	)
	(footprint ""
		(layer "F.Cu")
		(at 179.777644 -116.550186 180)
		(property "Reference" "R160"
			(at 0 0 180)
			(layer "F.SilkS")
			(hide yes)
			(effects
				(font
					(size 1.27 1.27)
				)
			)
		)
		(property "Value" ""
			(at 0 0 180)
			(layer "F.Fab")
			(effects
				(font
					(size 1.27 1.27)
				)
			)
		)
		(duplicate_pad_numbers_are_jumpers no)
		(fp_line
			(start 0.7874 0.4064)
			(end -0.7874 0.4064)
			(stroke
				(width 0.1524)
				(type default)
			)
			(layer "F.SilkS")
		)
		(fp_line
			(start 0.7874 -0.4064)
			(end 0.7874 0.4064)
			(stroke
				(width 0.1524)
				(type default)
			)
			(layer "F.SilkS")
		)
		(fp_line
			(start -0.7874 0.4064)
			(end -0.7874 -0.4064)
			(stroke
				(width 0.1524)
				(type default)
			)
			(layer "F.SilkS")
		)
		(fp_line
			(start -0.7874 -0.4064)
			(end 0.7874 -0.4064)
			(stroke
				(width 0.1524)
				(type default)
			)
			(layer "F.SilkS")
		)
		(fp_line
			(start 0.67945 0.3048)
			(end 0.120396 0.3048)
			(stroke
				(width 0.1)
				(type default)
			)
			(layer "F.Fab")
		)
		(fp_line
			(start 0.67945 -0.3048)
			(end 0.67945 0.3048)
			(stroke
				(width 0.1)
				(type default)
			)
			(layer "F.Fab")
		)
		(fp_line
			(start 0.12065 -0.2794)
			(end 0.12065 -0.3048)
			(stroke
				(width 0.1)
				(type default)
			)
			(layer "F.Fab")
		)
		(fp_line
			(start 0.12065 -0.3048)
			(end 0.67945 -0.3048)
			(stroke
				(width 0.1)
				(type default)
			)
			(layer "F.Fab")
		)
		(fp_line
			(start 0.120396 0.3048)
			(end 0.120396 0.2794)
			(stroke
				(width 0.1)
				(type default)
			)
			(layer "F.Fab")
		)
		(fp_line
			(start 0.120396 0.2794)
			(end -0.12065 0.2794)
			(stroke
				(width 0.1)
				(type default)
			)
			(layer "F.Fab")
		)
		(fp_line
			(start -0.12065 0.3048)
			(end -0.67945 0.3048)
			(stroke
				(width 0.1)
				(type default)
			)
			(layer "F.Fab")
		)
		(fp_line
			(start -0.12065 0.2794)
			(end -0.12065 0.3048)
			(stroke
				(width 0.1)
				(type default)
			)
			(layer "F.Fab")
		)
		(fp_line
			(start -0.12065 -0.2794)
			(end 0.12065 -0.2794)
			(stroke
				(width 0.1)
				(type default)
			)
			(layer "F.Fab")
		)
		(fp_line
			(start -0.12065 -0.305054)
			(end -0.12065 -0.2794)
			(stroke
				(width 0.1)
				(type default)
			)
			(layer "F.Fab")
		)
		(fp_line
			(start -0.67945 0.3048)
			(end -0.67945 -0.305054)
			(stroke
				(width 0.1)
				(type default)
			)
			(layer "F.Fab")
		)
		(fp_line
			(start -0.67945 -0.305054)
			(end -0.12065 -0.305054)
			(stroke
				(width 0.1)
				(type default)
			)
			(layer "F.Fab")
		)
		(pad "1" smd circle
			(at -0.40005 0 180)
			(size 0 0)
			(layers "F.Cu" "F.Mask" "F.Paste")
			(net "PRSNTB2_NIC3_N")
		)
		(pad "2" smd circle
			(at 0.40005 0 180)
			(size 0 0)
			(layers "F.Cu" "F.Mask" "F.Paste")
			(net "P3V3_AUX")
		)
	)
	(footprint ""
		(layer "F.Cu")
		(at 184.491884 -192.058798 180)
		(property "Reference" "R3291"
			(at 0 0 180)
			(layer "F.SilkS")
			(hide yes)
			(effects
				(font
					(size 1.27 1.27)
				)
			)
		)
		(property "Value" ""
			(at 0 0 180)
			(layer "F.Fab")
			(effects
				(font
					(size 1.27 1.27)
				)
			)
		)
		(duplicate_pad_numbers_are_jumpers no)
		(fp_line
			(start 0.7874 0.4064)
			(end -0.7874 0.4064)
			(stroke
				(width 0.1524)
				(type default)
			)
			(layer "F.SilkS")
		)
		(fp_line
			(start 0.7874 -0.4064)
			(end 0.7874 0.4064)
			(stroke
				(width 0.1524)
				(type default)
			)
			(layer "F.SilkS")
		)
		(fp_line
			(start -0.7874 0.4064)
			(end -0.7874 -0.4064)
			(stroke
				(width 0.1524)
				(type default)
			)
			(layer "F.SilkS")
		)
		(fp_line
			(start -0.7874 -0.4064)
			(end 0.7874 -0.4064)
			(stroke
				(width 0.1524)
				(type default)
			)
			(layer "F.SilkS")
		)
		(fp_line
			(start 0.67945 0.3048)
			(end 0.120396 0.3048)
			(stroke
				(width 0.1)
				(type default)
			)
			(layer "F.Fab")
		)
		(fp_line
			(start 0.67945 -0.3048)
			(end 0.67945 0.3048)
			(stroke
				(width 0.1)
				(type default)
			)
			(layer "F.Fab")
		)
		(fp_line
			(start 0.12065 -0.2794)
			(end 0.12065 -0.3048)
			(stroke
				(width 0.1)
				(type default)
			)
			(layer "F.Fab")
		)
		(fp_line
			(start 0.12065 -0.3048)
			(end 0.67945 -0.3048)
			(stroke
				(width 0.1)
				(type default)
			)
			(layer "F.Fab")
		)
		(fp_line
			(start 0.120396 0.3048)
			(end 0.120396 0.2794)
			(stroke
				(width 0.1)
				(type default)
			)
			(layer "F.Fab")
		)
		(fp_line
			(start 0.120396 0.2794)
			(end -0.12065 0.2794)
			(stroke
				(width 0.1)
				(type default)
			)
			(layer "F.Fab")
		)
		(fp_line
			(start -0.12065 0.3048)
			(end -0.67945 0.3048)
			(stroke
				(width 0.1)
				(type default)
			)
			(layer "F.Fab")
		)
		(fp_line
			(start -0.12065 0.2794)
			(end -0.12065 0.3048)
			(stroke
				(width 0.1)
				(type default)
			)
			(layer "F.Fab")
		)
		(fp_line
			(start -0.12065 -0.2794)
			(end 0.12065 -0.2794)
			(stroke
				(width 0.1)
				(type default)
			)
			(layer "F.Fab")
		)
		(fp_line
			(start -0.12065 -0.305054)
			(end -0.12065 -0.2794)
			(stroke
				(width 0.1)
				(type default)
			)
			(layer "F.Fab")
		)
		(fp_line
			(start -0.67945 0.3048)
			(end -0.67945 -0.305054)
			(stroke
				(width 0.1)
				(type default)
			)
			(layer "F.Fab")
		)
		(fp_line
			(start -0.67945 -0.305054)
			(end -0.12065 -0.305054)
			(stroke
				(width 0.1)
				(type default)
			)
			(layer "F.Fab")
		)
		(pad "1" smd circle
			(at -0.40005 0 180)
			(size 0 0)
			(layers "F.Cu" "F.Mask" "F.Paste")
			(net "SPI_BIC1_LS01_EN_N")
		)
		(pad "2" smd circle
			(at 0.40005 0 180)
			(size 0 0)
			(layers "F.Cu" "F.Mask" "F.Paste")
			(net "SPI_BIC1_LS01_EN_R_N")
		)
	)
	(footprint ""
		(layer "F.Cu")
		(at 338.151724 -108.054902 180)
		(property "Reference" "PC818"
			(at 0 0 180)
			(layer "F.SilkS")
			(hide yes)
			(effects
				(font
					(size 1.27 1.27)
				)
			)
		)
		(property "Value" ""
			(at 0 0 180)
			(layer "F.Fab")
			(effects
				(font
					(size 1.27 1.27)
				)
			)
		)
		(duplicate_pad_numbers_are_jumpers no)
		(fp_line
			(start 0.7874 0.4064)
			(end -0.7874 0.4064)
			(stroke
				(width 0.1524)
				(type default)
			)
			(layer "F.SilkS")
		)
		(fp_line
			(start 0.7874 -0.4064)
			(end 0.7874 0.4064)
			(stroke
				(width 0.1524)
				(type default)
			)
			(layer "F.SilkS")
		)
		(fp_line
			(start -0.7874 0.4064)
			(end -0.7874 -0.4064)
			(stroke
				(width 0.1524)
				(type default)
			)
			(layer "F.SilkS")
		)
		(fp_line
			(start -0.7874 -0.4064)
			(end 0.7874 -0.4064)
			(stroke
				(width 0.1524)
				(type default)
			)
			(layer "F.SilkS")
		)
		(fp_line
			(start 0.67945 0.3048)
			(end 0.120396 0.3048)
			(stroke
				(width 0.1)
				(type default)
			)
			(layer "F.Fab")
		)
		(fp_line
			(start 0.67945 -0.3048)
			(end 0.67945 0.3048)
			(stroke
				(width 0.1)
				(type default)
			)
			(layer "F.Fab")
		)
		(fp_line
			(start 0.12065 -0.2794)
			(end 0.12065 -0.3048)
			(stroke
				(width 0.1)
				(type default)
			)
			(layer "F.Fab")
		)
		(fp_line
			(start 0.12065 -0.3048)
			(end 0.67945 -0.3048)
			(stroke
				(width 0.1)
				(type default)
			)
			(layer "F.Fab")
		)
		(fp_line
			(start 0.120396 0.3048)
			(end 0.120396 0.2794)
			(stroke
				(width 0.1)
				(type default)
			)
			(layer "F.Fab")
		)
		(fp_line
			(start 0.120396 0.2794)
			(end -0.12065 0.2794)
			(stroke
				(width 0.1)
				(type default)
			)
			(layer "F.Fab")
		)
		(fp_line
			(start -0.12065 0.3048)
			(end -0.67945 0.3048)
			(stroke
				(width 0.1)
				(type default)
			)
			(layer "F.Fab")
		)
		(fp_line
			(start -0.12065 0.2794)
			(end -0.12065 0.3048)
			(stroke
				(width 0.1)
				(type default)
			)
			(layer "F.Fab")
		)
		(fp_line
			(start -0.12065 -0.2794)
			(end 0.12065 -0.2794)
			(stroke
				(width 0.1)
				(type default)
			)
			(layer "F.Fab")
		)
		(fp_line
			(start -0.12065 -0.305054)
			(end -0.12065 -0.2794)
			(stroke
				(width 0.1)
				(type default)
			)
			(layer "F.Fab")
		)
		(fp_line
			(start -0.67945 0.3048)
			(end -0.67945 -0.305054)
			(stroke
				(width 0.1)
				(type default)
			)
			(layer "F.Fab")
		)
		(fp_line
			(start -0.67945 -0.305054)
			(end -0.12065 -0.305054)
			(stroke
				(width 0.1)
				(type default)
			)
			(layer "F.Fab")
		)
		(pad "1" smd circle
			(at -0.40005 0 180)
			(size 0 0)
			(layers "F.Cu" "F.Mask" "F.Paste")
			(net "P12V_AUX")
		)
		(pad "2" smd circle
			(at 0.40005 0 180)
			(size 0 0)
			(layers "F.Cu" "F.Mask" "F.Paste")
			(net "GND")
		)
	)
	(footprint ""
		(layer "F.Cu")
		(at 221.990158 -79.595472)
		(property "Reference" "R5764"
			(at 0 0 0)
			(layer "F.SilkS")
			(hide yes)
			(effects
				(font
					(size 1.27 1.27)
				)
			)
		)
		(property "Value" ""
			(at 0 0 0)
			(layer "F.Fab")
			(effects
				(font
					(size 1.27 1.27)
				)
			)
		)
		(duplicate_pad_numbers_are_jumpers no)
		(fp_line
			(start -0.7874 -0.4064)
			(end 0.7874 -0.4064)
			(stroke
				(width 0.1524)
				(type default)
			)
			(layer "F.SilkS")
		)
		(fp_line
			(start -0.7874 0.4064)
			(end -0.7874 -0.4064)
			(stroke
				(width 0.1524)
				(type default)
			)
			(layer "F.SilkS")
		)
		(fp_line
			(start 0.7874 -0.4064)
			(end 0.7874 0.4064)
			(stroke
				(width 0.1524)
				(type default)
			)
			(layer "F.SilkS")
		)
		(fp_line
			(start 0.7874 0.4064)
			(end -0.7874 0.4064)
			(stroke
				(width 0.1524)
				(type default)
			)
			(layer "F.SilkS")
		)
		(fp_line
			(start -0.67945 -0.305054)
			(end -0.12065 -0.305054)
			(stroke
				(width 0.1)
				(type default)
			)
			(layer "F.Fab")
		)
		(fp_line
			(start -0.67945 0.3048)
			(end -0.67945 -0.305054)
			(stroke
				(width 0.1)
				(type default)
			)
			(layer "F.Fab")
		)
		(fp_line
			(start -0.12065 -0.305054)
			(end -0.12065 -0.2794)
			(stroke
				(width 0.1)
				(type default)
			)
			(layer "F.Fab")
		)
		(fp_line
			(start -0.12065 -0.2794)
			(end 0.12065 -0.2794)
			(stroke
				(width 0.1)
				(type default)
			)
			(layer "F.Fab")
		)
		(fp_line
			(start -0.12065 0.2794)
			(end -0.12065 0.3048)
			(stroke
				(width 0.1)
				(type default)
			)
			(layer "F.Fab")
		)
		(fp_line
			(start -0.12065 0.3048)
			(end -0.67945 0.3048)
			(stroke
				(width 0.1)
				(type default)
			)
			(layer "F.Fab")
		)
		(fp_line
			(start 0.120396 0.2794)
			(end -0.12065 0.2794)
			(stroke
				(width 0.1)
				(type default)
			)
			(layer "F.Fab")
		)
		(fp_line
			(start 0.120396 0.3048)
			(end 0.120396 0.2794)
			(stroke
				(width 0.1)
				(type default)
			)
			(layer "F.Fab")
		)
		(fp_line
			(start 0.12065 -0.3048)
			(end 0.67945 -0.3048)
			(stroke
				(width 0.1)
				(type default)
			)
			(layer "F.Fab")
		)
		(fp_line
			(start 0.12065 -0.2794)
			(end 0.12065 -0.3048)
			(stroke
				(width 0.1)
				(type default)
			)
			(layer "F.Fab")
		)
		(fp_line
			(start 0.67945 -0.3048)
			(end 0.67945 0.3048)
			(stroke
				(width 0.1)
				(type default)
			)
			(layer "F.Fab")
		)
		(fp_line
			(start 0.67945 0.3048)
			(end 0.120396 0.3048)
			(stroke
				(width 0.1)
				(type default)
			)
			(layer "F.Fab")
		)
		(pad "1" smd circle
			(at -0.40005 0)
			(size 0 0)
			(layers "F.Cu" "F.Mask" "F.Paste")
			(net "SSD10_LED")
		)
		(pad "2" smd circle
			(at 0.40005 0)
			(size 0 0)
			(layers "F.Cu" "F.Mask" "F.Paste")
			(net "SSD10_LED_R")
		)
	)
)
